(kicad_pcb
	(version 20260206)
	(generator "pcbnew")
	(generator_version "10.0")
	(general
		(thickness 1.6)
		(legacy_teardrops no)
	)
	(paper "A4")
	(title_block
		(title "peb — Lightning_PEB_BRD.brd")
		(comment 1 "Lightning (Wiwynn / Facebook NVMe JBOF) / footprints 842-848 of 2563")
	)
	(layers
		(0 "F.Cu" signal "TOP")
		(4 "In1.Cu" signal "L2GND")
		(6 "In2.Cu" signal "L3")
		(8 "In3.Cu" signal "L4VCC")
		(10 "In4.Cu" signal "L5VCC")
		(12 "In5.Cu" signal "L6")
		(14 "In6.Cu" signal "L7GND")
		(2 "B.Cu" signal "BOTTOM")
		(9 "F.Adhes" user "F.Adhesive")
		(11 "B.Adhes" user "B.Adhesive")
		(13 "F.Paste" user "Package Geometry/Pastemask Top")
		(15 "B.Paste" user "Package Geometry/Pastemask Bottom")
		(5 "F.SilkS" user "Ref Des/Silkscreen Top")
		(7 "B.SilkS" user "Ref Des/Silkscreen Bottom")
		(1 "F.Mask" user "Board Geometry/Soldermask Top")
		(3 "B.Mask" user "Board Geometry/Soldermask Bottom")
		(17 "Dwgs.User" user "User.Drawings")
		(19 "Cmts.User" user "User.Comments")
		(21 "Eco1.User" user "User.Eco1")
		(23 "Eco2.User" user "User.Eco2")
		(25 "Edge.Cuts" user "Board Geometry/Outline")
		(27 "Margin" user)
		(31 "F.CrtYd" user "Package Geometry/Place Bound Top")
		(29 "B.CrtYd" user "Package Geometry/Place Bound Bottom")
		(35 "F.Fab" user "Ref Des/Assembly Top")
		(33 "B.Fab" user "Ref Des/Assembly Bottom")
	)
	(footprint ""
		(layer "F.Cu")
		(at 87.8586 -185.6486 90)
		(property "Reference" "C4136"
			(at 0 0 90)
			(layer "F.SilkS")
			(hide yes)
			(effects
				(font
					(size 1.27 1.27)
				)
			)
		)
		(property "Value" "SCD1U25V3KX-GP"
			(at 0 -2.8194 90)
			(unlocked yes)
			(layer "F.Fab")
			(hide yes)
			(effects
				(font
					(size 1.016 1.016)
					(thickness 0.1524)
				)
			)
		)
		(property "Device Type" "C603H36"
			(at 0 -4.3434 90)
			(unlocked yes)
			(layer "F.Fab")
			(hide yes)
			(effects
				(font
					(size 1.016 1.016)
					(thickness 0.1524)
				)
			)
		)
		(duplicate_pad_numbers_are_jumpers no)
		(fp_line
			(start 0.508 0)
			(end -0.508 0)
			(stroke
				(width 0.2032)
				(type default)
			)
			(layer "F.SilkS")
		)
		(fp_rect
			(start -0.5842 1.3335)
			(end 0.5842 -1.3335)
			(stroke
				(width 0)
				(type default)
			)
			(fill no)
			(layer "F.CrtYd")
		)
		(fp_rect
			(start -0.5842 1.3335)
			(end 0.5842 -1.3335)
			(stroke
				(width 0)
				(type default)
			)
			(fill no)
			(layer "F.Fab")
		)
		(pad "1" smd custom
			(at 0 -0.762 90)
			(size 0.2159 0.2159)
			(layers "F.Cu" "F.Mask" "F.Paste")
			(net "GND")
			(options
				(clearance outline)
				(anchor circle)
			)
			(primitives
				(gr_poly
					(pts
						(arc
							(start -0.3302 -0.4318)
							(mid -0.402042 -0.402042)
							(end -0.4318 -0.3302)
						)
						(arc
							(start -0.4318 0.3302)
							(mid -0.402042 0.402042)
							(end -0.3302 0.4318)
						)
						(arc
							(start 0.3302 0.4318)
							(mid 0.402042 0.402042)
							(end 0.4318 0.3302)
						)
						(arc
							(start 0.4318 -0.3302)
							(mid 0.402042 -0.402042)
							(end 0.3302 -0.4318)
						)
					)
					(width 0)
					(fill yes)
				)
			)
		)
		(pad "2" smd custom
			(at 0 0.762 90)
			(size 0.2159 0.2159)
			(layers "F.Cu" "F.Mask" "F.Paste")
			(net "SSD_PWREN1_R")
			(options
				(clearance outline)
				(anchor circle)
			)
			(primitives
				(gr_poly
					(pts
						(arc
							(start -0.3302 -0.4318)
							(mid -0.402042 -0.402042)
							(end -0.4318 -0.3302)
						)
						(arc
							(start -0.4318 0.3302)
							(mid -0.402042 0.402042)
							(end -0.3302 0.4318)
						)
						(arc
							(start 0.3302 0.4318)
							(mid 0.402042 0.402042)
							(end 0.4318 0.3302)
						)
						(arc
							(start 0.4318 -0.3302)
							(mid 0.402042 -0.402042)
							(end 0.3302 -0.4318)
						)
					)
					(width 0)
					(fill yes)
				)
			)
		)
	)
	(footprint ""
		(layer "F.Cu")
		(at 205.359 -23.0124 -90)
		(property "Reference" "R835"
			(at 0 0 270)
			(layer "F.SilkS")
			(hide yes)
			(effects
				(font
					(size 1.27 1.27)
				)
			)
		)
		(property "Value" "4K7R2F-GP"
			(at 0.064008 -3.993896 270)
			(unlocked yes)
			(layer "F.Fab")
			(hide yes)
			(effects
				(font
					(size 1.016 1.016)
					(thickness 0.1524)
				)
			)
		)
		(property "Device Type" "R402H16"
			(at 0.064008 -5.517896 270)
			(unlocked yes)
			(layer "F.Fab")
			(hide yes)
			(effects
				(font
					(size 1.016 1.016)
					(thickness 0.1524)
				)
			)
		)
		(duplicate_pad_numbers_are_jumpers no)
		(fp_line
			(start -0.508 -0.9398)
			(end -0.508 0.9398)
			(stroke
				(width 0.1524)
				(type default)
			)
			(layer "F.SilkS")
		)
		(fp_line
			(start 0.508 -0.9398)
			(end -0.508 -0.9398)
			(stroke
				(width 0.1524)
				(type default)
			)
			(layer "F.SilkS")
		)
		(fp_rect
			(start -0.508 0.9398)
			(end 0.508 -0.9398)
			(stroke
				(width 0)
				(type default)
			)
			(fill no)
			(layer "F.CrtYd")
		)
		(fp_rect
			(start -0.508 0.9398)
			(end 0.508 -0.9398)
			(stroke
				(width 0)
				(type default)
			)
			(fill no)
			(layer "F.Fab")
		)
		(pad "1" smd custom
			(at 0 -0.4445 270)
			(size 0.1397 0.1397)
			(layers "F.Cu" "F.Mask" "F.Paste")
			(net "P3V3_STBY")
			(options
				(clearance outline)
				(anchor circle)
			)
			(primitives
				(gr_poly
					(pts
						(arc
							(start -0.1778 -0.2794)
							(mid -0.249642 -0.249642)
							(end -0.2794 -0.1778)
						)
						(arc
							(start -0.2794 0.1778)
							(mid -0.249642 0.249642)
							(end -0.1778 0.2794)
						)
						(arc
							(start 0.1778 0.2794)
							(mid 0.249642 0.249642)
							(end 0.2794 0.1778)
						)
						(arc
							(start 0.2794 -0.1778)
							(mid 0.249642 -0.249642)
							(end 0.1778 -0.2794)
						)
					)
					(width 0)
					(fill yes)
				)
			)
		)
		(pad "2" smd custom
			(at 0 0.4445 270)
			(size 0.1397 0.1397)
			(layers "F.Cu" "F.Mask" "F.Paste")
			(net "U56_INT_N")
			(options
				(clearance outline)
				(anchor circle)
			)
			(primitives
				(gr_poly
					(pts
						(arc
							(start -0.1778 -0.2794)
							(mid -0.249642 -0.249642)
							(end -0.2794 -0.1778)
						)
						(arc
							(start -0.2794 0.1778)
							(mid -0.249642 0.249642)
							(end -0.1778 0.2794)
						)
						(arc
							(start 0.1778 0.2794)
							(mid 0.249642 0.249642)
							(end 0.2794 0.1778)
						)
						(arc
							(start 0.2794 -0.1778)
							(mid 0.249642 -0.249642)
							(end 0.1778 -0.2794)
						)
					)
					(width 0)
					(fill yes)
				)
			)
		)
	)
	(footprint ""
		(layer "F.Cu")
		(at 118.364 -17.0688)
		(property "Reference" "R748"
			(at 0 0 0)
			(layer "F.SilkS")
			(hide yes)
			(effects
				(font
					(size 1.27 1.27)
				)
			)
		)
		(property "Value" "4K7R2F-GP"
			(at 0.064008 -3.993896 0)
			(unlocked yes)
			(layer "F.Fab")
			(hide yes)
			(effects
				(font
					(size 1.016 1.016)
					(thickness 0.1524)
				)
			)
		)
		(property "Device Type" "R402H16"
			(at 0.064008 -5.517896 0)
			(unlocked yes)
			(layer "F.Fab")
			(hide yes)
			(effects
				(font
					(size 1.016 1.016)
					(thickness 0.1524)
				)
			)
		)
		(duplicate_pad_numbers_are_jumpers no)
		(fp_line
			(start -0.508 -0.9398)
			(end -0.508 0.9398)
			(stroke
				(width 0.1524)
				(type default)
			)
			(layer "F.SilkS")
		)
		(fp_line
			(start 0.508 -0.9398)
			(end -0.508 -0.9398)
			(stroke
				(width 0.1524)
				(type default)
			)
			(layer "F.SilkS")
		)
		(fp_rect
			(start -0.508 0.9398)
			(end 0.508 -0.9398)
			(stroke
				(width 0)
				(type default)
			)
			(fill no)
			(layer "F.CrtYd")
		)
		(fp_rect
			(start -0.508 0.9398)
			(end 0.508 -0.9398)
			(stroke
				(width 0)
				(type default)
			)
			(fill no)
			(layer "F.Fab")
		)
		(pad "1" smd custom
			(at 0 -0.4445)
			(size 0.1397 0.1397)
			(layers "F.Cu" "F.Mask" "F.Paste")
			(net "U54_A1")
			(options
				(clearance outline)
				(anchor circle)
			)
			(primitives
				(gr_poly
					(pts
						(arc
							(start -0.1778 -0.2794)
							(mid -0.249642 -0.249642)
							(end -0.2794 -0.1778)
						)
						(arc
							(start -0.2794 0.1778)
							(mid -0.249642 0.249642)
							(end -0.1778 0.2794)
						)
						(arc
							(start 0.1778 0.2794)
							(mid 0.249642 0.249642)
							(end 0.2794 0.1778)
						)
						(arc
							(start 0.2794 -0.1778)
							(mid 0.249642 -0.249642)
							(end 0.1778 -0.2794)
						)
					)
					(width 0)
					(fill yes)
				)
			)
		)
		(pad "2" smd custom
			(at 0 0.4445)
			(size 0.1397 0.1397)
			(layers "F.Cu" "F.Mask" "F.Paste")
			(net "P3V3_STBY")
			(options
				(clearance outline)
				(anchor circle)
			)
			(primitives
				(gr_poly
					(pts
						(arc
							(start -0.1778 -0.2794)
							(mid -0.249642 -0.249642)
							(end -0.2794 -0.1778)
						)
						(arc
							(start -0.2794 0.1778)
							(mid -0.249642 0.249642)
							(end -0.1778 0.2794)
						)
						(arc
							(start 0.1778 0.2794)
							(mid 0.249642 0.249642)
							(end 0.2794 0.1778)
						)
						(arc
							(start 0.2794 -0.1778)
							(mid 0.249642 -0.249642)
							(end 0.1778 -0.2794)
						)
					)
					(width 0)
					(fill yes)
				)
			)
		)
	)
	(footprint ""
		(layer "F.Cu")
		(at 326.771 -86.487)
		(property "Reference" "R4168"
			(at 0 0 0)
			(layer "F.SilkS")
			(hide yes)
			(effects
				(font
					(size 1.27 1.27)
				)
			)
		)
		(property "Value" "4K7R2F-GP"
			(at 0.064008 -3.993896 0)
			(unlocked yes)
			(layer "F.Fab")
			(hide yes)
			(effects
				(font
					(size 1.016 1.016)
					(thickness 0.1524)
				)
			)
		)
		(property "Device Type" "R402H16"
			(at 0.064008 -5.517896 0)
			(unlocked yes)
			(layer "F.Fab")
			(hide yes)
			(effects
				(font
					(size 1.016 1.016)
					(thickness 0.1524)
				)
			)
		)
		(duplicate_pad_numbers_are_jumpers no)
		(fp_line
			(start -0.508 -0.9398)
			(end -0.508 0.9398)
			(stroke
				(width 0.1524)
				(type default)
			)
			(layer "F.SilkS")
		)
		(fp_line
			(start 0.508 -0.9398)
			(end -0.508 -0.9398)
			(stroke
				(width 0.1524)
				(type default)
			)
			(layer "F.SilkS")
		)
		(fp_rect
			(start -0.508 0.9398)
			(end 0.508 -0.9398)
			(stroke
				(width 0)
				(type default)
			)
			(fill no)
			(layer "F.CrtYd")
		)
		(fp_rect
			(start -0.508 0.9398)
			(end 0.508 -0.9398)
			(stroke
				(width 0)
				(type default)
			)
			(fill no)
			(layer "F.Fab")
		)
		(pad "1" smd custom
			(at 0 -0.4445)
			(size 0.1397 0.1397)
			(layers "F.Cu" "F.Mask" "F.Paste")
			(net "UPLINK4")
			(options
				(clearance outline)
				(anchor circle)
			)
			(primitives
				(gr_poly
					(pts
						(arc
							(start -0.1778 -0.2794)
							(mid -0.249642 -0.249642)
							(end -0.2794 -0.1778)
						)
						(arc
							(start -0.2794 0.1778)
							(mid -0.249642 0.249642)
							(end -0.1778 0.2794)
						)
						(arc
							(start 0.1778 0.2794)
							(mid 0.249642 0.249642)
							(end 0.2794 0.1778)
						)
						(arc
							(start 0.2794 -0.1778)
							(mid 0.249642 -0.249642)
							(end 0.1778 -0.2794)
						)
					)
					(width 0)
					(fill yes)
				)
			)
		)
		(pad "2" smd custom
			(at 0 0.4445)
			(size 0.1397 0.1397)
			(layers "F.Cu" "F.Mask" "F.Paste")
			(net "P3V3_STBY")
			(options
				(clearance outline)
				(anchor circle)
			)
			(primitives
				(gr_poly
					(pts
						(arc
							(start -0.1778 -0.2794)
							(mid -0.249642 -0.249642)
							(end -0.2794 -0.1778)
						)
						(arc
							(start -0.2794 0.1778)
							(mid -0.249642 0.249642)
							(end -0.1778 0.2794)
						)
						(arc
							(start 0.1778 0.2794)
							(mid 0.249642 0.249642)
							(end 0.2794 0.1778)
						)
						(arc
							(start 0.2794 -0.1778)
							(mid 0.249642 -0.249642)
							(end 0.1778 -0.2794)
						)
					)
					(width 0)
					(fill yes)
				)
			)
		)
	)
	(footprint ""
		(layer "F.Cu")
		(at 73.406 -32.004 -90)
		(property "Reference" "PR27"
			(at 0 0 270)
			(layer "F.SilkS")
			(hide yes)
			(effects
				(font
					(size 1.27 1.27)
				)
			)
		)
		(property "Value" "10R3F-GP"
			(at -0.0254 -2.5146 270)
			(unlocked yes)
			(layer "F.Fab")
			(hide yes)
			(effects
				(font
					(size 1.016 1.016)
					(thickness 0.1524)
				)
			)
		)
		(property "Device Type" "R603H22"
			(at -0.0254 -4.0386 270)
			(unlocked yes)
			(layer "F.Fab")
			(hide yes)
			(effects
				(font
					(size 1.016 1.016)
					(thickness 0.1524)
				)
			)
		)
		(duplicate_pad_numbers_are_jumpers no)
		(fp_line
			(start -0.4826 0)
			(end -0.2032 0)
			(stroke
				(width 0.2032)
				(type default)
			)
			(layer "F.SilkS")
		)
		(fp_line
			(start 0.2032 0)
			(end 0.4826 0)
			(stroke
				(width 0.2032)
				(type default)
			)
			(layer "F.SilkS")
		)
		(fp_rect
			(start -0.5842 1.3335)
			(end 0.5842 -1.3335)
			(stroke
				(width 0)
				(type default)
			)
			(fill no)
			(layer "F.CrtYd")
		)
		(fp_rect
			(start -0.5842 1.3335)
			(end 0.5842 -1.3335)
			(stroke
				(width 0)
				(type default)
			)
			(fill no)
			(layer "F.Fab")
		)
		(pad "1" smd custom
			(at 0 -0.762 270)
			(size 0.2159 0.2159)
			(layers "F.Cu" "F.Mask" "F.Paste")
			(net "P3V3_PWR")
			(options
				(clearance outline)
				(anchor circle)
			)
			(primitives
				(gr_poly
					(pts
						(arc
							(start -0.3302 -0.4318)
							(mid -0.402042 -0.402042)
							(end -0.4318 -0.3302)
						)
						(arc
							(start -0.4318 0.3302)
							(mid -0.402042 0.402042)
							(end -0.3302 0.4318)
						)
						(arc
							(start 0.3302 0.4318)
							(mid 0.402042 0.402042)
							(end 0.4318 0.3302)
						)
						(arc
							(start 0.4318 -0.3302)
							(mid 0.402042 -0.402042)
							(end 0.3302 -0.4318)
						)
					)
					(width 0)
					(fill yes)
				)
			)
		)
		(pad "2" smd custom
			(at 0 0.762 270)
			(size 0.2159 0.2159)
			(layers "F.Cu" "F.Mask" "F.Paste")
			(net "P3V3_STBY_VFB_R")
			(options
				(clearance outline)
				(anchor circle)
			)
			(primitives
				(gr_poly
					(pts
						(arc
							(start -0.3302 -0.4318)
							(mid -0.402042 -0.402042)
							(end -0.4318 -0.3302)
						)
						(arc
							(start -0.4318 0.3302)
							(mid -0.402042 0.402042)
							(end -0.3302 0.4318)
						)
						(arc
							(start 0.3302 0.4318)
							(mid 0.402042 0.402042)
							(end 0.4318 0.3302)
						)
						(arc
							(start 0.4318 -0.3302)
							(mid 0.402042 -0.402042)
							(end 0.3302 -0.4318)
						)
					)
					(width 0)
					(fill yes)
				)
			)
		)
	)
	(footprint ""
		(layer "F.Cu")
		(at 154.813 -90.267282 180)
		(property "Reference" "C412"
			(at 0 0 180)
			(layer "F.SilkS")
			(hide yes)
			(effects
				(font
					(size 1.27 1.27)
				)
			)
		)
		(property "Value" "SC12P50V2JN-3GP"
			(at 1.1811 -2.7051 180)
			(unlocked yes)
			(layer "F.Fab")
			(hide yes)
			(effects
				(font
					(size 1.016 1.016)
					(thickness 0.1524)
				)
			)
		)
		(property "Device Type" "C402H24"
			(at 1.1811 -4.2291 180)
			(unlocked yes)
			(layer "F.Fab")
			(hide yes)
			(effects
				(font
					(size 1.016 1.016)
					(thickness 0.1524)
				)
			)
		)
		(duplicate_pad_numbers_are_jumpers no)
		(fp_rect
			(start -0.4318 0.9525)
			(end 0.4318 -0.9525)
			(stroke
				(width 0)
				(type default)
			)
			(fill no)
			(layer "F.CrtYd")
		)
		(fp_rect
			(start -0.4318 0.9525)
			(end 0.4318 -0.9525)
			(stroke
				(width 0)
				(type default)
			)
			(fill no)
			(layer "F.Fab")
		)
		(pad "1" smd custom
			(at 0 -0.4445 180)
			(size 0.1524 0.1524)
			(layers "F.Cu" "F.Mask" "F.Paste")
			(net "XTAL_X2")
			(options
				(clearance outline)
				(anchor circle)
			)
			(primitives
				(gr_poly
					(pts
						(arc
							(start 0.3048 -0.2032)
							(mid 0.275042 -0.275042)
							(end 0.2032 -0.3048)
						)
						(arc
							(start -0.2032 -0.3048)
							(mid -0.275042 -0.275042)
							(end -0.3048 -0.2032)
						)
						(arc
							(start -0.3048 0.2032)
							(mid -0.275042 0.275042)
							(end -0.2032 0.3048)
						)
						(arc
							(start 0.2032 0.3048)
							(mid 0.275042 0.275042)
							(end 0.3048 0.2032)
						)
					)
					(width 0)
					(fill yes)
				)
			)
		)
		(pad "2" smd custom
			(at 0 0.4445 180)
			(size 0.1524 0.1524)
			(layers "F.Cu" "F.Mask" "F.Paste")
			(net "GND")
			(options
				(clearance outline)
				(anchor circle)
			)
			(primitives
				(gr_poly
					(pts
						(arc
							(start 0.3048 -0.2032)
							(mid 0.275042 -0.275042)
							(end 0.2032 -0.3048)
						)
						(arc
							(start -0.2032 -0.3048)
							(mid -0.275042 -0.275042)
							(end -0.3048 -0.2032)
						)
						(arc
							(start -0.3048 0.2032)
							(mid -0.275042 0.275042)
							(end -0.2032 0.3048)
						)
						(arc
							(start 0.2032 0.3048)
							(mid 0.275042 0.275042)
							(end 0.3048 0.2032)
						)
					)
					(width 0)
					(fill yes)
				)
			)
		)
	)
	(footprint ""
		(layer "F.Cu")
		(at 153.113232 -53.222398)
		(property "Reference" "PQ19"
			(at 0 0 0)
			(layer "F.SilkS")
			(hide yes)
			(effects
				(font
					(size 1.27 1.27)
				)
			)
		)
		(property "Value" "AO3400-GP-U"
			(at 0.0254 -12.3444 0)
			(unlocked yes)
			(layer "F.Fab")
			(hide yes)
			(effects
				(font
					(size 1.016 1.016)
					(thickness 0.1524)
				)
			)
		)
		(property "Device Type" "SOT23DGS2D8H50"
			(at 0.0254 -14.2494 0)
			(unlocked yes)
			(layer "F.Fab")
			(hide yes)
			(effects
				(font
					(size 1.016 1.016)
					(thickness 0.1524)
				)
			)
		)
		(duplicate_pad_numbers_are_jumpers no)
		(fp_line
			(start -1.7018 -0.254)
			(end 1.7018 -0.254)
			(stroke
				(width 0.1524)
				(type default)
			)
			(layer "F.SilkS")
		)
		(fp_line
			(start -1.7018 0.254)
			(end -1.7018 -0.254)
			(stroke
				(width 0.1524)
				(type default)
			)
			(layer "F.SilkS")
		)
		(fp_line
			(start 1.7018 -0.254)
			(end 1.7018 0.254)
			(stroke
				(width 0.1524)
				(type default)
			)
			(layer "F.SilkS")
		)
		(fp_line
			(start 1.7018 0.254)
			(end -1.7018 0.254)
			(stroke
				(width 0.1524)
				(type default)
			)
			(layer "F.SilkS")
		)
		(fp_rect
			(start -1.778 1.9812)
			(end 1.778 -1.9812)
			(stroke
				(width 0)
				(type default)
			)
			(fill no)
			(layer "F.CrtYd")
		)
		(fp_poly
			(pts
				(xy -1.778 -1.9812) (xy 1.778 -1.9812) (xy 1.778 1.9812) (xy -1.778 1.9812)
			)
			(stroke
				(width 0)
				(type default)
			)
			(fill no)
			(layer "F.Fab")
		)
		(pad "D" smd custom
			(at 0 -1.1176)
			(size 0.254 0.254)
			(layers "F.Cu" "F.Mask" "F.Paste")
			(net "P0V9_VFB_AVS")
			(options
				(clearance outline)
				(anchor circle)
			)
			(primitives
				(gr_poly
					(pts
						(arc
							(start -0.508 -0.4064)
							(mid -0.448484 -0.550084)
							(end -0.3048 -0.6096)
						)
						(arc
							(start 0.3048 -0.6096)
							(mid 0.448484 -0.550084)
							(end 0.508 -0.4064)
						)
						(arc
							(start 0.508 0.4064)
							(mid 0.448484 0.550084)
							(end 0.3048 0.6096)
						)
						(arc
							(start -0.3048 0.6096)
							(mid -0.448484 0.550084)
							(end -0.508 0.4064)
						)
					)
					(width 0)
					(fill yes)
				)
			)
		)
		(pad "G" smd custom
			(at -1.016 1.1176)
			(size 0.254 0.254)
			(layers "F.Cu" "F.Mask" "F.Paste")
			(net "AVS_ENB1_R")
			(options
				(clearance outline)
				(anchor circle)
			)
			(primitives
				(gr_poly
					(pts
						(arc
							(start -0.508 -0.4064)
							(mid -0.448484 -0.550084)
							(end -0.3048 -0.6096)
						)
						(arc
							(start 0.3048 -0.6096)
							(mid 0.448484 -0.550084)
							(end 0.508 -0.4064)
						)
						(arc
							(start 0.508 0.4064)
							(mid 0.448484 0.550084)
							(end 0.3048 0.6096)
						)
						(arc
							(start -0.3048 0.6096)
							(mid -0.448484 0.550084)
							(end -0.508 0.4064)
						)
					)
					(width 0)
					(fill yes)
				)
			)
		)
		(pad "S" smd custom
			(at 1.016 1.1176)
			(size 0.254 0.254)
			(layers "F.Cu" "F.Mask" "F.Paste")
			(net "AGND_P0V9")
			(options
				(clearance outline)
				(anchor circle)
			)
			(primitives
				(gr_poly
					(pts
						(arc
							(start -0.508 -0.4064)
							(mid -0.448484 -0.550084)
							(end -0.3048 -0.6096)
						)
						(arc
							(start 0.3048 -0.6096)
							(mid 0.448484 -0.550084)
							(end 0.508 -0.4064)
						)
						(arc
							(start 0.508 0.4064)
							(mid 0.448484 0.550084)
							(end 0.3048 0.6096)
						)
						(arc
							(start -0.3048 0.6096)
							(mid -0.448484 0.550084)
							(end -0.508 0.4064)
						)
					)
					(width 0)
					(fill yes)
				)
			)
		)
	)
)
